(kicad_pcb
	(version 20260206)
	(generator "pcbnew")
	(generator_version "10.0")
	(general
		(thickness 1.6)
		(legacy_teardrops no)
	)
	(paper "A4")
	(title_block
		(title "dpb — 14545-sa.0730WZS0815.brd")
		(comment 1 "Honey Badger (Wiwynn) / footprints 387-392 of 1066")
	)
	(layers
		(0 "F.Cu" signal "TOP")
		(4 "In1.Cu" signal "L2GND")
		(6 "In2.Cu" signal "L3")
		(8 "In3.Cu" signal "L4VCC")
		(10 "In4.Cu" signal "L5VCC")
		(12 "In5.Cu" signal "L6")
		(14 "In6.Cu" signal "L7GND")
		(2 "B.Cu" signal "BOTTOM")
		(9 "F.Adhes" user "F.Adhesive")
		(11 "B.Adhes" user "B.Adhesive")
		(13 "F.Paste" user "Package Geometry/Pastemask Top")
		(15 "B.Paste" user "Package Geometry/Pastemask Bottom")
		(5 "F.SilkS" user "Ref Des/Silkscreen Top")
		(7 "B.SilkS" user "Ref Des/Silkscreen Bottom")
		(1 "F.Mask" user "Board Geometry/Soldermask Top")
		(3 "B.Mask" user "Board Geometry/Soldermask Bottom")
		(17 "Dwgs.User" user "User.Drawings")
		(19 "Cmts.User" user "User.Comments")
		(21 "Eco1.User" user "User.Eco1")
		(23 "Eco2.User" user "User.Eco2")
		(25 "Edge.Cuts" user "Board Geometry/Outline")
		(27 "Margin" user)
		(31 "F.CrtYd" user "Package Geometry/Place Bound Top")
		(29 "B.CrtYd" user "Package Geometry/Place Bound Bottom")
		(35 "F.Fab" user "Ref Des/Assembly Top")
		(33 "B.Fab" user "Ref Des/Assembly Bottom")
	)
	(footprint ""
		(layer "F.Cu")
		(at 19.240246 -468.150702 -90)
		(property "Reference" "R242"
			(at 0 0 270)
			(layer "F.SilkS")
			(hide yes)
			(effects
				(font
					(size 1.27 1.27)
				)
			)
		)
		(property "Value" "0R2J-2-GP"
			(at 0.064008 -3.993896 270)
			(unlocked yes)
			(layer "F.Fab")
			(hide yes)
			(effects
				(font
					(size 1.016 1.016)
					(thickness 0.1524)
				)
			)
		)
		(property "Device Type" "R402H16"
			(at 0.064008 -5.517896 270)
			(unlocked yes)
			(layer "F.Fab")
			(hide yes)
			(effects
				(font
					(size 1.016 1.016)
					(thickness 0.1524)
				)
			)
		)
		(duplicate_pad_numbers_are_jumpers no)
		(fp_line
			(start -0.508 -0.9398)
			(end -0.508 0.9398)
			(stroke
				(width 0.1524)
				(type default)
			)
			(layer "F.SilkS")
		)
		(fp_line
			(start 0.508 -0.9398)
			(end -0.508 -0.9398)
			(stroke
				(width 0.1524)
				(type default)
			)
			(layer "F.SilkS")
		)
		(fp_rect
			(start -0.508 0.9398)
			(end 0.508 -0.9398)
			(stroke
				(width 0)
				(type default)
			)
			(fill no)
			(layer "F.CrtYd")
		)
		(fp_rect
			(start -0.508 0.9398)
			(end 0.508 -0.9398)
			(stroke
				(width 0)
				(type default)
			)
			(fill no)
			(layer "F.Fab")
		)
		(pad "1" smd custom
			(at 0 -0.4445 270)
			(size 0.1397 0.1397)
			(layers "F.Cu" "F.Mask" "F.Paste")
			(net "DRV_ACT_NET10")
			(options
				(clearance outline)
				(anchor circle)
			)
			(primitives
				(gr_poly
					(pts
						(arc
							(start -0.1778 -0.2794)
							(mid -0.249642 -0.249642)
							(end -0.2794 -0.1778)
						)
						(arc
							(start -0.2794 0.1778)
							(mid -0.249642 0.249642)
							(end -0.1778 0.2794)
						)
						(arc
							(start 0.1778 0.2794)
							(mid 0.249642 0.249642)
							(end 0.2794 0.1778)
						)
						(arc
							(start 0.2794 -0.1778)
							(mid 0.249642 -0.249642)
							(end 0.1778 -0.2794)
						)
					)
					(width 0)
					(fill yes)
				)
			)
		)
		(pad "2" smd custom
			(at 0 0.4445 270)
			(size 0.1397 0.1397)
			(layers "F.Cu" "F.Mask" "F.Paste")
			(net "DRIVE_ACT_10")
			(options
				(clearance outline)
				(anchor circle)
			)
			(primitives
				(gr_poly
					(pts
						(arc
							(start -0.1778 -0.2794)
							(mid -0.249642 -0.249642)
							(end -0.2794 -0.1778)
						)
						(arc
							(start -0.2794 0.1778)
							(mid -0.249642 0.249642)
							(end -0.1778 0.2794)
						)
						(arc
							(start 0.1778 0.2794)
							(mid 0.249642 0.249642)
							(end 0.2794 0.1778)
						)
						(arc
							(start 0.2794 -0.1778)
							(mid 0.249642 -0.249642)
							(end 0.1778 -0.2794)
						)
					)
					(width 0)
					(fill yes)
				)
			)
		)
	)
	(footprint ""
		(layer "F.Cu")
		(at 40.436546 -131.7879 180)
		(property "Reference" "R315"
			(at 0 0 180)
			(layer "F.SilkS")
			(hide yes)
			(effects
				(font
					(size 1.27 1.27)
				)
			)
		)
		(property "Value" "4K7R2J-2-GP"
			(at 0.064008 -3.993896 180)
			(unlocked yes)
			(layer "F.Fab")
			(hide yes)
			(effects
				(font
					(size 1.016 1.016)
					(thickness 0.1524)
				)
			)
		)
		(property "Device Type" "R402H16"
			(at 0.064008 -5.517896 180)
			(unlocked yes)
			(layer "F.Fab")
			(hide yes)
			(effects
				(font
					(size 1.016 1.016)
					(thickness 0.1524)
				)
			)
		)
		(duplicate_pad_numbers_are_jumpers no)
		(fp_line
			(start 0.508 -0.9398)
			(end -0.508 -0.9398)
			(stroke
				(width 0.1524)
				(type default)
			)
			(layer "F.SilkS")
		)
		(fp_line
			(start -0.508 -0.9398)
			(end -0.508 0.9398)
			(stroke
				(width 0.1524)
				(type default)
			)
			(layer "F.SilkS")
		)
		(fp_rect
			(start -0.508 0.9398)
			(end 0.508 -0.9398)
			(stroke
				(width 0)
				(type default)
			)
			(fill no)
			(layer "F.CrtYd")
		)
		(fp_rect
			(start -0.508 0.9398)
			(end 0.508 -0.9398)
			(stroke
				(width 0)
				(type default)
			)
			(fill no)
			(layer "F.Fab")
		)
		(pad "1" smd custom
			(at 0 -0.4445 180)
			(size 0.1397 0.1397)
			(layers "F.Cu" "F.Mask" "F.Paste")
			(net "P3V3")
			(options
				(clearance outline)
				(anchor circle)
			)
			(primitives
				(gr_poly
					(pts
						(arc
							(start -0.1778 -0.2794)
							(mid -0.249642 -0.249642)
							(end -0.2794 -0.1778)
						)
						(arc
							(start -0.2794 0.1778)
							(mid -0.249642 0.249642)
							(end -0.1778 0.2794)
						)
						(arc
							(start 0.1778 0.2794)
							(mid 0.249642 0.249642)
							(end 0.2794 0.1778)
						)
						(arc
							(start 0.2794 -0.1778)
							(mid 0.249642 -0.249642)
							(end 0.1778 -0.2794)
						)
					)
					(width 0)
					(fill yes)
				)
			)
		)
		(pad "2" smd custom
			(at 0 0.4445 180)
			(size 0.1397 0.1397)
			(layers "F.Cu" "F.Mask" "F.Paste")
			(net "I2C_B_TMP2_A2")
			(options
				(clearance outline)
				(anchor circle)
			)
			(primitives
				(gr_poly
					(pts
						(arc
							(start -0.1778 -0.2794)
							(mid -0.249642 -0.249642)
							(end -0.2794 -0.1778)
						)
						(arc
							(start -0.2794 0.1778)
							(mid -0.249642 0.249642)
							(end -0.1778 0.2794)
						)
						(arc
							(start 0.1778 0.2794)
							(mid 0.249642 0.249642)
							(end 0.2794 0.1778)
						)
						(arc
							(start 0.2794 -0.1778)
							(mid 0.249642 -0.249642)
							(end 0.1778 -0.2794)
						)
					)
					(width 0)
					(fill yes)
				)
			)
		)
	)
	(footprint ""
		(layer "F.Cu")
		(at 218.142058 -378.662184)
		(property "Reference" "C131"
			(at 0 0 0)
			(layer "F.SilkS")
			(hide yes)
			(effects
				(font
					(size 1.27 1.27)
				)
			)
		)
		(property "Value" "SCD01U50V2KX-1GP"
			(at 1.1811 -2.7051 0)
			(unlocked yes)
			(layer "F.Fab")
			(hide yes)
			(effects
				(font
					(size 1.016 1.016)
					(thickness 0.1524)
				)
			)
		)
		(property "Device Type" "C402H22"
			(at 1.1811 -4.2291 0)
			(unlocked yes)
			(layer "F.Fab")
			(hide yes)
			(effects
				(font
					(size 1.016 1.016)
					(thickness 0.1524)
				)
			)
		)
		(duplicate_pad_numbers_are_jumpers no)
		(fp_rect
			(start -0.4318 0.9525)
			(end 0.4318 -0.9525)
			(stroke
				(width 0)
				(type default)
			)
			(fill no)
			(layer "F.CrtYd")
		)
		(fp_rect
			(start -0.4318 0.9525)
			(end 0.4318 -0.9525)
			(stroke
				(width 0)
				(type default)
			)
			(fill no)
			(layer "F.Fab")
		)
		(pad "1" smd custom
			(at 0 -0.4445)
			(size 0.1524 0.1524)
			(layers "F.Cu" "F.Mask" "F.Paste")
			(net "HDD_PRSNT_NET1")
			(options
				(clearance outline)
				(anchor circle)
			)
			(primitives
				(gr_poly
					(pts
						(arc
							(start 0.3048 -0.2032)
							(mid 0.275042 -0.275042)
							(end 0.2032 -0.3048)
						)
						(arc
							(start -0.2032 -0.3048)
							(mid -0.275042 -0.275042)
							(end -0.3048 -0.2032)
						)
						(arc
							(start -0.3048 0.2032)
							(mid -0.275042 0.275042)
							(end -0.2032 0.3048)
						)
						(arc
							(start 0.2032 0.3048)
							(mid 0.275042 0.275042)
							(end 0.3048 0.2032)
						)
					)
					(width 0)
					(fill yes)
				)
			)
		)
		(pad "2" smd custom
			(at 0 0.4445)
			(size 0.1524 0.1524)
			(layers "F.Cu" "F.Mask" "F.Paste")
			(net "GND")
			(options
				(clearance outline)
				(anchor circle)
			)
			(primitives
				(gr_poly
					(pts
						(arc
							(start 0.3048 -0.2032)
							(mid 0.275042 -0.275042)
							(end 0.2032 -0.3048)
						)
						(arc
							(start -0.2032 -0.3048)
							(mid -0.275042 -0.275042)
							(end -0.3048 -0.2032)
						)
						(arc
							(start -0.3048 0.2032)
							(mid -0.275042 0.275042)
							(end -0.2032 0.3048)
						)
						(arc
							(start 0.2032 0.3048)
							(mid 0.275042 0.275042)
							(end 0.3048 0.2032)
						)
					)
					(width 0)
					(fill yes)
				)
			)
		)
	)
	(footprint ""
		(layer "F.Cu")
		(at 52.958746 -212.372702 -90)
		(property "Reference" "U38"
			(at 0 0 270)
			(layer "F.SilkS")
			(hide yes)
			(effects
				(font
					(size 1.27 1.27)
				)
			)
		)
		(property "Value" "P2003EVG-GP"
			(at 0 -11.1252 270)
			(unlocked yes)
			(layer "F.Fab")
			(hide yes)
			(effects
				(font
					(size 1.016 1.016)
					(thickness 0.1524)
				)
			)
		)
		(property "Device Type" "SOIC8H79"
			(at 0 -12.6492 270)
			(unlocked yes)
			(layer "F.Fab")
			(hide yes)
			(effects
				(font
					(size 1.016 1.016)
					(thickness 0.1524)
				)
			)
		)
		(duplicate_pad_numbers_are_jumpers no)
		(fp_line
			(start -2.6162 3.429)
			(end -2.6162 1.4732)
			(stroke
				(width 0.4064)
				(type default)
			)
			(layer "F.SilkS")
		)
		(fp_line
			(start -2.7432 1.4224)
			(end 2.1336 1.4224)
			(stroke
				(width 0.1524)
				(type default)
			)
			(layer "F.SilkS")
		)
		(fp_line
			(start 2.1336 1.4224)
			(end 2.1336 -1.4224)
			(stroke
				(width 0.1524)
				(type default)
			)
			(layer "F.SilkS")
		)
		(fp_line
			(start -2.2352 0)
			(end -2.7432 0.508)
			(stroke
				(width 0.1524)
				(type default)
			)
			(layer "F.SilkS")
		)
		(fp_line
			(start -2.7432 -0.508)
			(end -2.2352 0)
			(stroke
				(width 0.1524)
				(type default)
			)
			(layer "F.SilkS")
		)
		(fp_line
			(start -2.7432 -1.4224)
			(end -2.7432 1.4224)
			(stroke
				(width 0.1524)
				(type default)
			)
			(layer "F.SilkS")
		)
		(fp_line
			(start 2.1336 -1.4224)
			(end -2.7432 -1.4224)
			(stroke
				(width 0.1524)
				(type default)
			)
			(layer "F.SilkS")
		)
		(fp_poly
			(pts
				(xy 2.2098 -1.4224) (xy 2.2098 1.4224) (xy -2.2225 1.4224) (xy -2.2225 -1.4224)
			)
			(stroke
				(width 0)
				(type default)
			)
			(fill yes)
			(layer "F.SilkS")
		)
		(fp_rect
			(start -2.4511 2.9972)
			(end 2.4511 -2.9972)
			(stroke
				(width 0)
				(type default)
			)
			(fill no)
			(layer "F.CrtYd")
		)
		(fp_poly
			(pts
				(xy -2.8194 3.6322) (xy -2.8194 -3.6322) (xy 2.8194 -3.6322) (xy 2.8194 -2.2987) (xy 2.4511 -2.2987)
				(xy 2.4511 -2.9972) (xy -2.4511 -2.9972) (xy -2.4511 2.9972) (xy 2.4511 2.9972) (xy 2.4511 -2.286)
				(xy 2.8194 -2.286) (xy 2.8194 3.6322)
			)
			(stroke
				(width 0)
				(type default)
			)
			(fill no)
			(layer "F.CrtYd")
		)
		(fp_rect
			(start -2.8194 3.6322)
			(end 2.8194 -3.6322)
			(stroke
				(width 0)
				(type default)
			)
			(fill no)
			(layer "F.Fab")
		)
		(pad "1" smd rect
			(at -1.905 2.54 270)
			(size 0.635 1.651)
			(layers "F.Cu" "F.Mask" "F.Paste")
			(net "P12V")
		)
		(pad "2" smd rect
			(at -0.635 2.54 270)
			(size 0.635 1.651)
			(layers "F.Cu" "F.Mask" "F.Paste")
			(net "P12V")
		)
		(pad "3" smd rect
			(at 0.635 2.54 270)
			(size 0.635 1.651)
			(layers "F.Cu" "F.Mask" "F.Paste")
			(net "P12V")
		)
		(pad "4" smd rect
			(at 1.905 2.54 270)
			(size 0.635 1.651)
			(layers "F.Cu" "F.Mask" "F.Paste")
			(net "SW_HDD12_N")
		)
		(pad "5" smd rect
			(at 1.905 -2.54 270)
			(size 0.635 1.651)
			(layers "F.Cu" "F.Mask" "F.Paste")
			(net "P12V_HDD12")
		)
		(pad "6" smd rect
			(at 0.635 -2.54 270)
			(size 0.635 1.651)
			(layers "F.Cu" "F.Mask" "F.Paste")
			(net "P12V_HDD12")
		)
		(pad "7" smd rect
			(at -0.635 -2.54 270)
			(size 0.635 1.651)
			(layers "F.Cu" "F.Mask" "F.Paste")
			(net "P12V_HDD12")
		)
		(pad "8" smd rect
			(at -1.905 -2.54 270)
			(size 0.635 1.651)
			(layers "F.Cu" "F.Mask" "F.Paste")
			(net "P12V_HDD12")
		)
	)
	(footprint ""
		(layer "F.Cu")
		(at 37.718746 -310.797702 -90)
		(property "Reference" "U35"
			(at 0 0 270)
			(layer "F.SilkS")
			(hide yes)
			(effects
				(font
					(size 1.27 1.27)
				)
			)
		)
		(property "Value" "P2003EVG-GP"
			(at 0 -11.1252 270)
			(unlocked yes)
			(layer "F.Fab")
			(hide yes)
			(effects
				(font
					(size 1.016 1.016)
					(thickness 0.1524)
				)
			)
		)
		(property "Device Type" "SOIC8H79"
			(at 0 -12.6492 270)
			(unlocked yes)
			(layer "F.Fab")
			(hide yes)
			(effects
				(font
					(size 1.016 1.016)
					(thickness 0.1524)
				)
			)
		)
		(duplicate_pad_numbers_are_jumpers no)
		(fp_line
			(start -2.6162 3.429)
			(end -2.6162 1.4732)
			(stroke
				(width 0.4064)
				(type default)
			)
			(layer "F.SilkS")
		)
		(fp_line
			(start -2.7432 1.4224)
			(end 2.1336 1.4224)
			(stroke
				(width 0.1524)
				(type default)
			)
			(layer "F.SilkS")
		)
		(fp_line
			(start 2.1336 1.4224)
			(end 2.1336 -1.4224)
			(stroke
				(width 0.1524)
				(type default)
			)
			(layer "F.SilkS")
		)
		(fp_line
			(start -2.2352 0)
			(end -2.7432 0.508)
			(stroke
				(width 0.1524)
				(type default)
			)
			(layer "F.SilkS")
		)
		(fp_line
			(start -2.7432 -0.508)
			(end -2.2352 0)
			(stroke
				(width 0.1524)
				(type default)
			)
			(layer "F.SilkS")
		)
		(fp_line
			(start -2.7432 -1.4224)
			(end -2.7432 1.4224)
			(stroke
				(width 0.1524)
				(type default)
			)
			(layer "F.SilkS")
		)
		(fp_line
			(start 2.1336 -1.4224)
			(end -2.7432 -1.4224)
			(stroke
				(width 0.1524)
				(type default)
			)
			(layer "F.SilkS")
		)
		(fp_poly
			(pts
				(xy 2.2098 -1.4224) (xy 2.2098 1.4224) (xy -2.2225 1.4224) (xy -2.2225 -1.4224)
			)
			(stroke
				(width 0)
				(type default)
			)
			(fill yes)
			(layer "F.SilkS")
		)
		(fp_rect
			(start -2.4511 2.9972)
			(end 2.4511 -2.9972)
			(stroke
				(width 0)
				(type default)
			)
			(fill no)
			(layer "F.CrtYd")
		)
		(fp_poly
			(pts
				(xy -2.8194 3.6322) (xy -2.8194 -3.6322) (xy 2.8194 -3.6322) (xy 2.8194 -2.2987) (xy 2.4511 -2.2987)
				(xy 2.4511 -2.9972) (xy -2.4511 -2.9972) (xy -2.4511 2.9972) (xy 2.4511 2.9972) (xy 2.4511 -2.286)
				(xy 2.8194 -2.286) (xy 2.8194 3.6322)
			)
			(stroke
				(width 0)
				(type default)
			)
			(fill no)
			(layer "F.CrtYd")
		)
		(fp_rect
			(start -2.8194 3.6322)
			(end 2.8194 -3.6322)
			(stroke
				(width 0)
				(type default)
			)
			(fill no)
			(layer "F.Fab")
		)
		(pad "1" smd rect
			(at -1.905 2.54 270)
			(size 0.635 1.651)
			(layers "F.Cu" "F.Mask" "F.Paste")
			(net "P12V")
		)
		(pad "2" smd rect
			(at -0.635 2.54 270)
			(size 0.635 1.651)
			(layers "F.Cu" "F.Mask" "F.Paste")
			(net "P12V")
		)
		(pad "3" smd rect
			(at 0.635 2.54 270)
			(size 0.635 1.651)
			(layers "F.Cu" "F.Mask" "F.Paste")
			(net "P12V")
		)
		(pad "4" smd rect
			(at 1.905 2.54 270)
			(size 0.635 1.651)
			(layers "F.Cu" "F.Mask" "F.Paste")
			(net "SW_HDD11_N")
		)
		(pad "5" smd rect
			(at 1.905 -2.54 270)
			(size 0.635 1.651)
			(layers "F.Cu" "F.Mask" "F.Paste")
			(net "P12V_HDD11")
		)
		(pad "6" smd rect
			(at 0.635 -2.54 270)
			(size 0.635 1.651)
			(layers "F.Cu" "F.Mask" "F.Paste")
			(net "P12V_HDD11")
		)
		(pad "7" smd rect
			(at -0.635 -2.54 270)
			(size 0.635 1.651)
			(layers "F.Cu" "F.Mask" "F.Paste")
			(net "P12V_HDD11")
		)
		(pad "8" smd rect
			(at -1.905 -2.54 270)
			(size 0.635 1.651)
			(layers "F.Cu" "F.Mask" "F.Paste")
			(net "P12V_HDD11")
		)
	)
	(footprint ""
		(layer "F.Cu")
		(at 30.734 -282.829 90)
		(property "Reference" "C371"
			(at 0 0 90)
			(layer "F.SilkS")
			(hide yes)
			(effects
				(font
					(size 1.27 1.27)
				)
			)
		)
		(property "Value" "SCD033U25V2KX-GP"
			(at 1.1811 -2.7051 90)
			(unlocked yes)
			(layer "F.Fab")
			(hide yes)
			(effects
				(font
					(size 1.016 1.016)
					(thickness 0.1524)
				)
			)
		)
		(property "Device Type" "C402H22"
			(at 1.1811 -4.2291 90)
			(unlocked yes)
			(layer "F.Fab")
			(hide yes)
			(effects
				(font
					(size 1.016 1.016)
					(thickness 0.1524)
				)
			)
		)
		(duplicate_pad_numbers_are_jumpers no)
		(fp_rect
			(start -0.4318 0.9525)
			(end 0.4318 -0.9525)
			(stroke
				(width 0)
				(type default)
			)
			(fill no)
			(layer "F.CrtYd")
		)
		(fp_rect
			(start -0.4318 0.9525)
			(end 0.4318 -0.9525)
			(stroke
				(width 0)
				(type default)
			)
			(fill no)
			(layer "F.Fab")
		)
		(pad "1" smd custom
			(at 0 -0.4445 90)
			(size 0.1524 0.1524)
			(layers "F.Cu" "F.Mask" "F.Paste")
			(net "SW_HDD7_P")
			(options
				(clearance outline)
				(anchor circle)
			)
			(primitives
				(gr_poly
					(pts
						(arc
							(start 0.3048 -0.2032)
							(mid 0.275042 -0.275042)
							(end 0.2032 -0.3048)
						)
						(arc
							(start -0.2032 -0.3048)
							(mid -0.275042 -0.275042)
							(end -0.3048 -0.2032)
						)
						(arc
							(start -0.3048 0.2032)
							(mid -0.275042 0.275042)
							(end -0.2032 0.3048)
						)
						(arc
							(start 0.2032 0.3048)
							(mid 0.275042 0.275042)
							(end 0.3048 0.2032)
						)
					)
					(width 0)
					(fill yes)
				)
			)
		)
		(pad "2" smd custom
			(at 0 0.4445 90)
			(size 0.1524 0.1524)
			(layers "F.Cu" "F.Mask" "F.Paste")
			(net "GND")
			(options
				(clearance outline)
				(anchor circle)
			)
			(primitives
				(gr_poly
					(pts
						(arc
							(start 0.3048 -0.2032)
							(mid 0.275042 -0.275042)
							(end 0.2032 -0.3048)
						)
						(arc
							(start -0.2032 -0.3048)
							(mid -0.275042 -0.275042)
							(end -0.3048 -0.2032)
						)
						(arc
							(start -0.3048 0.2032)
							(mid -0.275042 0.275042)
							(end -0.2032 0.3048)
						)
						(arc
							(start 0.2032 0.3048)
							(mid 0.275042 0.275042)
							(end 0.3048 0.2032)
						)
					)
					(width 0)
					(fill yes)
				)
			)
		)
	)
)
